(kicad_pcb
	(version 20260206)
	(generator "pcbnew")
	(generator_version "10.0")
	(general
		(thickness 1.6)
		(legacy_teardrops no)
	)
	(paper "A4")
	(title_block
		(title "baseboard — 13948-1b.1110WZS1818.brd")
		(comment 1 "Honey Badger (Wiwynn) / footprints 587-594 of 2523")
	)
	(layers
		(0 "F.Cu" signal "TOP")
		(4 "In1.Cu" signal "L2GND")
		(6 "In2.Cu" signal "L3")
		(8 "In3.Cu" signal "L4VCC")
		(10 "In4.Cu" signal "L5VCC")
		(12 "In5.Cu" signal "L6")
		(14 "In6.Cu" signal "L7GND")
		(2 "B.Cu" signal "BOTTOM")
		(9 "F.Adhes" user "F.Adhesive")
		(11 "B.Adhes" user "B.Adhesive")
		(13 "F.Paste" user "Package Geometry/Pastemask Top")
		(15 "B.Paste" user "Package Geometry/Pastemask Bottom")
		(5 "F.SilkS" user "Ref Des/Silkscreen Top")
		(7 "B.SilkS" user "Ref Des/Silkscreen Bottom")
		(1 "F.Mask" user "Board Geometry/Soldermask Top")
		(3 "B.Mask" user "Board Geometry/Soldermask Bottom")
		(17 "Dwgs.User" user "User.Drawings")
		(19 "Cmts.User" user "User.Comments")
		(21 "Eco1.User" user "User.Eco1")
		(23 "Eco2.User" user "User.Eco2")
		(25 "Edge.Cuts" user "Board Geometry/Outline")
		(27 "Margin" user)
		(31 "F.CrtYd" user "Package Geometry/Place Bound Top")
		(29 "B.CrtYd" user "Package Geometry/Place Bound Bottom")
		(35 "F.Fab" user "Ref Des/Assembly Top")
		(33 "B.Fab" user "Ref Des/Assembly Bottom")
	)
	(footprint ""
		(layer "F.Cu")
		(at 223.72828 -88.86952 180)
		(property "Reference" "SC1297"
			(at 0 0 180)
			(layer "F.SilkS")
			(hide yes)
			(effects
				(font
					(size 1.27 1.27)
				)
			)
		)
		(property "Value" "SCD1U16V2KX-3GP"
			(at 1.1811 -2.7051 180)
			(unlocked yes)
			(layer "F.Fab")
			(hide yes)
			(effects
				(font
					(size 1.016 1.016)
					(thickness 0.1524)
				)
			)
		)
		(property "Device Type" "C402H22"
			(at 1.1811 -4.2291 180)
			(unlocked yes)
			(layer "F.Fab")
			(hide yes)
			(effects
				(font
					(size 1.016 1.016)
					(thickness 0.1524)
				)
			)
		)
		(duplicate_pad_numbers_are_jumpers no)
		(fp_rect
			(start -0.4318 0.9525)
			(end 0.4318 -0.9525)
			(stroke
				(width 0)
				(type default)
			)
			(fill no)
			(layer "F.CrtYd")
		)
		(fp_rect
			(start -0.4318 0.9525)
			(end 0.4318 -0.9525)
			(stroke
				(width 0)
				(type default)
			)
			(fill no)
			(layer "F.Fab")
		)
		(pad "1" smd custom
			(at 0 -0.4445 180)
			(size 0.1524 0.1524)
			(layers "F.Cu" "F.Mask" "F.Paste")
			(net "P3V3_STBY")
			(options
				(clearance outline)
				(anchor circle)
			)
			(primitives
				(gr_poly
					(pts
						(arc
							(start 0.3048 -0.2032)
							(mid 0.275042 -0.275042)
							(end 0.2032 -0.3048)
						)
						(arc
							(start -0.2032 -0.3048)
							(mid -0.275042 -0.275042)
							(end -0.3048 -0.2032)
						)
						(arc
							(start -0.3048 0.2032)
							(mid -0.275042 0.275042)
							(end -0.2032 0.3048)
						)
						(arc
							(start 0.2032 0.3048)
							(mid 0.275042 0.275042)
							(end 0.3048 0.2032)
						)
					)
					(width 0)
					(fill yes)
				)
			)
		)
		(pad "2" smd custom
			(at 0 0.4445 180)
			(size 0.1524 0.1524)
			(layers "F.Cu" "F.Mask" "F.Paste")
			(net "GND")
			(options
				(clearance outline)
				(anchor circle)
			)
			(primitives
				(gr_poly
					(pts
						(arc
							(start 0.3048 -0.2032)
							(mid 0.275042 -0.275042)
							(end 0.2032 -0.3048)
						)
						(arc
							(start -0.2032 -0.3048)
							(mid -0.275042 -0.275042)
							(end -0.3048 -0.2032)
						)
						(arc
							(start -0.3048 0.2032)
							(mid -0.275042 0.275042)
							(end -0.2032 0.3048)
						)
						(arc
							(start 0.2032 0.3048)
							(mid 0.275042 0.275042)
							(end 0.3048 0.2032)
						)
					)
					(width 0)
					(fill yes)
				)
			)
		)
	)
	(footprint ""
		(layer "F.Cu")
		(at 167.503348 -125.085856 180)
		(property "Reference" "PC190"
			(at 0 0 180)
			(layer "F.SilkS")
			(hide yes)
			(effects
				(font
					(size 1.27 1.27)
				)
			)
		)
		(property "Value" "SC1U16V3KX-2GP"
			(at 0 -2.8194 180)
			(unlocked yes)
			(layer "F.Fab")
			(hide yes)
			(effects
				(font
					(size 1.016 1.016)
					(thickness 0.1524)
				)
			)
		)
		(property "Device Type" "C603H36"
			(at 0 -4.3434 180)
			(unlocked yes)
			(layer "F.Fab")
			(hide yes)
			(effects
				(font
					(size 1.016 1.016)
					(thickness 0.1524)
				)
			)
		)
		(duplicate_pad_numbers_are_jumpers no)
		(fp_line
			(start 0.508 0)
			(end -0.508 0)
			(stroke
				(width 0.2032)
				(type default)
			)
			(layer "F.SilkS")
		)
		(fp_rect
			(start -0.5842 1.3335)
			(end 0.5842 -1.3335)
			(stroke
				(width 0)
				(type default)
			)
			(fill no)
			(layer "F.CrtYd")
		)
		(fp_rect
			(start -0.5842 1.3335)
			(end 0.5842 -1.3335)
			(stroke
				(width 0)
				(type default)
			)
			(fill no)
			(layer "F.Fab")
		)
		(pad "1" smd custom
			(at 0 -0.762 180)
			(size 0.2159 0.2159)
			(layers "F.Cu" "F.Mask" "F.Paste")
			(net "P0V9_E_VREG")
			(options
				(clearance outline)
				(anchor circle)
			)
			(primitives
				(gr_poly
					(pts
						(arc
							(start -0.3302 -0.4318)
							(mid -0.402042 -0.402042)
							(end -0.4318 -0.3302)
						)
						(arc
							(start -0.4318 0.3302)
							(mid -0.402042 0.402042)
							(end -0.3302 0.4318)
						)
						(arc
							(start 0.3302 0.4318)
							(mid 0.402042 0.402042)
							(end 0.4318 0.3302)
						)
						(arc
							(start 0.4318 -0.3302)
							(mid 0.402042 -0.402042)
							(end 0.3302 -0.4318)
						)
					)
					(width 0)
					(fill yes)
				)
			)
		)
		(pad "2" smd custom
			(at 0 0.762 180)
			(size 0.2159 0.2159)
			(layers "F.Cu" "F.Mask" "F.Paste")
			(net "GND")
			(options
				(clearance outline)
				(anchor circle)
			)
			(primitives
				(gr_poly
					(pts
						(arc
							(start -0.3302 -0.4318)
							(mid -0.402042 -0.402042)
							(end -0.4318 -0.3302)
						)
						(arc
							(start -0.4318 0.3302)
							(mid -0.402042 0.402042)
							(end -0.3302 0.4318)
						)
						(arc
							(start 0.3302 0.4318)
							(mid 0.402042 0.402042)
							(end 0.4318 0.3302)
						)
						(arc
							(start 0.4318 -0.3302)
							(mid 0.402042 -0.402042)
							(end 0.3302 -0.4318)
						)
					)
					(width 0)
					(fill yes)
				)
			)
		)
	)
	(footprint ""
		(layer "F.Cu")
		(at 208.915 -103.124 180)
		(property "Reference" "PR122"
			(at 0 0 180)
			(layer "F.SilkS")
			(hide yes)
			(effects
				(font
					(size 1.27 1.27)
				)
			)
		)
		(property "Value" "4K22R2F-GP"
			(at 0.064008 -3.993896 180)
			(unlocked yes)
			(layer "F.Fab")
			(hide yes)
			(effects
				(font
					(size 1.016 1.016)
					(thickness 0.1524)
				)
			)
		)
		(property "Device Type" "R402H16"
			(at 0.064008 -5.517896 180)
			(unlocked yes)
			(layer "F.Fab")
			(hide yes)
			(effects
				(font
					(size 1.016 1.016)
					(thickness 0.1524)
				)
			)
		)
		(duplicate_pad_numbers_are_jumpers no)
		(fp_line
			(start 0.508 -0.9398)
			(end -0.508 -0.9398)
			(stroke
				(width 0.1524)
				(type default)
			)
			(layer "F.SilkS")
		)
		(fp_line
			(start -0.508 -0.9398)
			(end -0.508 0.9398)
			(stroke
				(width 0.1524)
				(type default)
			)
			(layer "F.SilkS")
		)
		(fp_rect
			(start -0.508 0.9398)
			(end 0.508 -0.9398)
			(stroke
				(width 0)
				(type default)
			)
			(fill no)
			(layer "F.CrtYd")
		)
		(fp_rect
			(start -0.508 0.9398)
			(end 0.508 -0.9398)
			(stroke
				(width 0)
				(type default)
			)
			(fill no)
			(layer "F.Fab")
		)
		(pad "1" smd custom
			(at 0 -0.4445 180)
			(size 0.1397 0.1397)
			(layers "F.Cu" "F.Mask" "F.Paste")
			(net "P1V5_C")
			(options
				(clearance outline)
				(anchor circle)
			)
			(primitives
				(gr_poly
					(pts
						(arc
							(start -0.1778 -0.2794)
							(mid -0.249642 -0.249642)
							(end -0.2794 -0.1778)
						)
						(arc
							(start -0.2794 0.1778)
							(mid -0.249642 0.249642)
							(end -0.1778 0.2794)
						)
						(arc
							(start 0.1778 0.2794)
							(mid 0.249642 0.249642)
							(end 0.2794 0.1778)
						)
						(arc
							(start 0.2794 -0.1778)
							(mid 0.249642 -0.249642)
							(end 0.1778 -0.2794)
						)
					)
					(width 0)
					(fill yes)
				)
			)
		)
		(pad "2" smd custom
			(at 0 0.4445 180)
			(size 0.1397 0.1397)
			(layers "F.Cu" "F.Mask" "F.Paste")
			(net "TPS74801_1V5_C_FB")
			(options
				(clearance outline)
				(anchor circle)
			)
			(primitives
				(gr_poly
					(pts
						(arc
							(start -0.1778 -0.2794)
							(mid -0.249642 -0.249642)
							(end -0.2794 -0.1778)
						)
						(arc
							(start -0.2794 0.1778)
							(mid -0.249642 0.249642)
							(end -0.1778 0.2794)
						)
						(arc
							(start 0.1778 0.2794)
							(mid 0.249642 0.249642)
							(end 0.2794 0.1778)
						)
						(arc
							(start 0.2794 -0.1778)
							(mid 0.249642 -0.249642)
							(end 0.1778 -0.2794)
						)
					)
					(width 0)
					(fill yes)
				)
			)
		)
	)
	(footprint ""
		(layer "F.Cu")
		(at 250.00204 -50.039778)
		(property "Reference" "SC1064"
			(at 0 0 0)
			(layer "F.SilkS")
			(hide yes)
			(effects
				(font
					(size 1.27 1.27)
				)
			)
		)
		(property "Value" "SCD1U16V2KX-3GP"
			(at 1.1811 -2.7051 0)
			(unlocked yes)
			(layer "F.Fab")
			(hide yes)
			(effects
				(font
					(size 1.016 1.016)
					(thickness 0.1524)
				)
			)
		)
		(property "Device Type" "C402H22"
			(at 1.1811 -4.2291 0)
			(unlocked yes)
			(layer "F.Fab")
			(hide yes)
			(effects
				(font
					(size 1.016 1.016)
					(thickness 0.1524)
				)
			)
		)
		(duplicate_pad_numbers_are_jumpers no)
		(fp_rect
			(start -0.4318 0.9525)
			(end 0.4318 -0.9525)
			(stroke
				(width 0)
				(type default)
			)
			(fill no)
			(layer "F.CrtYd")
		)
		(fp_rect
			(start -0.4318 0.9525)
			(end 0.4318 -0.9525)
			(stroke
				(width 0)
				(type default)
			)
			(fill no)
			(layer "F.Fab")
		)
		(pad "1" smd custom
			(at 0 -0.4445)
			(size 0.1524 0.1524)
			(layers "F.Cu" "F.Mask" "F.Paste")
			(net "P1V8_C")
			(options
				(clearance outline)
				(anchor circle)
			)
			(primitives
				(gr_poly
					(pts
						(arc
							(start 0.3048 -0.2032)
							(mid 0.275042 -0.275042)
							(end 0.2032 -0.3048)
						)
						(arc
							(start -0.2032 -0.3048)
							(mid -0.275042 -0.275042)
							(end -0.3048 -0.2032)
						)
						(arc
							(start -0.3048 0.2032)
							(mid -0.275042 0.275042)
							(end -0.2032 0.3048)
						)
						(arc
							(start 0.2032 0.3048)
							(mid 0.275042 0.275042)
							(end 0.3048 0.2032)
						)
					)
					(width 0)
					(fill yes)
				)
			)
		)
		(pad "2" smd custom
			(at 0 0.4445)
			(size 0.1524 0.1524)
			(layers "F.Cu" "F.Mask" "F.Paste")
			(net "GND")
			(options
				(clearance outline)
				(anchor circle)
			)
			(primitives
				(gr_poly
					(pts
						(arc
							(start 0.3048 -0.2032)
							(mid 0.275042 -0.275042)
							(end 0.2032 -0.3048)
						)
						(arc
							(start -0.2032 -0.3048)
							(mid -0.275042 -0.275042)
							(end -0.3048 -0.2032)
						)
						(arc
							(start -0.3048 0.2032)
							(mid -0.275042 0.275042)
							(end -0.2032 0.3048)
						)
						(arc
							(start 0.2032 0.3048)
							(mid 0.275042 0.275042)
							(end 0.3048 0.2032)
						)
					)
					(width 0)
					(fill yes)
				)
			)
		)
	)
	(footprint ""
		(layer "F.Cu")
		(at 14.936216 -181.91988 180)
		(property "Reference" "R654"
			(at 0 0 180)
			(layer "F.SilkS")
			(hide yes)
			(effects
				(font
					(size 1.27 1.27)
				)
			)
		)
		(property "Value" "4K7R2F-GP"
			(at 0.064008 -3.993896 180)
			(unlocked yes)
			(layer "F.Fab")
			(hide yes)
			(effects
				(font
					(size 1.016 1.016)
					(thickness 0.1524)
				)
			)
		)
		(property "Device Type" "R402H16"
			(at 0.064008 -5.517896 180)
			(unlocked yes)
			(layer "F.Fab")
			(hide yes)
			(effects
				(font
					(size 1.016 1.016)
					(thickness 0.1524)
				)
			)
		)
		(duplicate_pad_numbers_are_jumpers no)
		(fp_line
			(start 0.508 -0.9398)
			(end -0.508 -0.9398)
			(stroke
				(width 0.1524)
				(type default)
			)
			(layer "F.SilkS")
		)
		(fp_line
			(start -0.508 -0.9398)
			(end -0.508 0.9398)
			(stroke
				(width 0.1524)
				(type default)
			)
			(layer "F.SilkS")
		)
		(fp_rect
			(start -0.508 0.9398)
			(end 0.508 -0.9398)
			(stroke
				(width 0)
				(type default)
			)
			(fill no)
			(layer "F.CrtYd")
		)
		(fp_rect
			(start -0.508 0.9398)
			(end 0.508 -0.9398)
			(stroke
				(width 0)
				(type default)
			)
			(fill no)
			(layer "F.Fab")
		)
		(pad "1" smd custom
			(at 0 -0.4445 180)
			(size 0.1397 0.1397)
			(layers "F.Cu" "F.Mask" "F.Paste")
			(net "P3V3_STBY")
			(options
				(clearance outline)
				(anchor circle)
			)
			(primitives
				(gr_poly
					(pts
						(arc
							(start -0.1778 -0.2794)
							(mid -0.249642 -0.249642)
							(end -0.2794 -0.1778)
						)
						(arc
							(start -0.2794 0.1778)
							(mid -0.249642 0.249642)
							(end -0.1778 0.2794)
						)
						(arc
							(start 0.1778 0.2794)
							(mid 0.249642 0.249642)
							(end 0.2794 0.1778)
						)
						(arc
							(start 0.2794 -0.1778)
							(mid 0.249642 -0.249642)
							(end 0.1778 -0.2794)
						)
					)
					(width 0)
					(fill yes)
				)
			)
		)
		(pad "2" smd custom
			(at 0 0.4445 180)
			(size 0.1397 0.1397)
			(layers "F.Cu" "F.Mask" "F.Paste")
			(net "IO_EXP_HDD_PRE_A2")
			(options
				(clearance outline)
				(anchor circle)
			)
			(primitives
				(gr_poly
					(pts
						(arc
							(start -0.1778 -0.2794)
							(mid -0.249642 -0.249642)
							(end -0.2794 -0.1778)
						)
						(arc
							(start -0.2794 0.1778)
							(mid -0.249642 0.249642)
							(end -0.1778 0.2794)
						)
						(arc
							(start 0.1778 0.2794)
							(mid 0.249642 0.249642)
							(end 0.2794 0.1778)
						)
						(arc
							(start 0.2794 -0.1778)
							(mid 0.249642 -0.249642)
							(end 0.1778 -0.2794)
						)
					)
					(width 0)
					(fill yes)
				)
			)
		)
	)
	(footprint ""
		(layer "F.Cu")
		(at 101.727 -68.9356 -90)
		(property "Reference" "SL3"
			(at 0 0 270)
			(layer "F.SilkS")
			(hide yes)
			(effects
				(font
					(size 1.27 1.27)
				)
			)
		)
		(property "Value" "MPZ2012S601AT-GP"
			(at 0 -4.2418 270)
			(unlocked yes)
			(layer "F.Fab")
			(hide yes)
			(effects
				(font
					(size 1.016 1.016)
					(thickness 0.1524)
				)
			)
		)
		(property "Device Type" "L805H42"
			(at 0 -5.7912 270)
			(unlocked yes)
			(layer "F.Fab")
			(hide yes)
			(effects
				(font
					(size 1.016 1.016)
					(thickness 0.1524)
				)
			)
		)
		(duplicate_pad_numbers_are_jumpers no)
		(fp_line
			(start -0.889 1.7018)
			(end -0.889 -1.7018)
			(stroke
				(width 0.1524)
				(type default)
			)
			(layer "F.SilkS")
		)
		(fp_line
			(start 0.889 1.7018)
			(end -0.889 1.7018)
			(stroke
				(width 0.1524)
				(type default)
			)
			(layer "F.SilkS")
		)
		(fp_line
			(start -0.889 -1.7018)
			(end 0.889 -1.7018)
			(stroke
				(width 0.1524)
				(type default)
			)
			(layer "F.SilkS")
		)
		(fp_line
			(start 0.889 -1.7018)
			(end 0.889 1.7018)
			(stroke
				(width 0.1524)
				(type default)
			)
			(layer "F.SilkS")
		)
		(fp_rect
			(start -0.9652 1.778)
			(end 0.9652 -1.778)
			(stroke
				(width 0)
				(type default)
			)
			(fill no)
			(layer "F.CrtYd")
		)
		(fp_rect
			(start -0.9652 1.778)
			(end 0.9652 -1.778)
			(stroke
				(width 0)
				(type default)
			)
			(fill no)
			(layer "F.Fab")
		)
		(pad "1" smd rect
			(at 0 -0.9652 270)
			(size 1.397 1.143)
			(layers "F.Cu" "F.Mask" "F.Paste")
			(net "HM40ADC_VDDA")
		)
		(pad "2" smd rect
			(at 0 0.9652 270)
			(size 1.397 1.143)
			(layers "F.Cu" "F.Mask" "F.Paste")
			(net "P1V8_C")
		)
	)
	(footprint ""
		(layer "F.Cu")
		(at 109.05617 -77.7494)
		(property "Reference" "STP66"
			(at 0 0 0)
			(layer "F.SilkS")
			(hide yes)
			(effects
				(font
					(size 1.27 1.27)
				)
			)
		)
		(property "Value" "TPAD28"
			(at 0.0127 -1.8034 0)
			(unlocked yes)
			(layer "F.Fab")
			(hide yes)
			(effects
				(font
					(size 1.016 1.016)
					(thickness 0.1524)
				)
			)
		)
		(property "Device Type" "TPAD28"
			(at 0.0127 -3.3274 0)
			(unlocked yes)
			(layer "F.Fab")
			(hide yes)
			(effects
				(font
					(size 1.016 1.016)
					(thickness 0.1524)
				)
			)
		)
		(duplicate_pad_numbers_are_jumpers no)
		(fp_poly
			(pts
				(arc
					(start 0.3556 0)
					(mid -0.3556 0)
					(end 0.3556 0)
				)
			)
			(stroke
				(width 0)
				(type default)
			)
			(fill no)
			(layer "F.CrtYd")
		)
		(fp_poly
			(pts
				(arc
					(start 0.6096 0)
					(mid -0.6096 0)
					(end 0.6096 0)
				)
			)
			(stroke
				(width 0)
				(type default)
			)
			(fill no)
			(layer "F.Fab")
		)
		(pad "1" smd circle
			(at 0 0)
			(size 0.7112 0.7112)
			(layers "F.Cu" "F.Mask" "F.Paste")
			(net "EXP_TEST_MUX28")
		)
	)
	(footprint ""
		(layer "F.Cu")
		(at 89.154 -231.775 180)
		(property "Reference" "R662"
			(at 0 0 180)
			(layer "F.SilkS")
			(hide yes)
			(effects
				(font
					(size 1.27 1.27)
				)
			)
		)
		(property "Value" "0R2J-2-GP"
			(at 0.064008 -3.993896 180)
			(unlocked yes)
			(layer "F.Fab")
			(hide yes)
			(effects
				(font
					(size 1.016 1.016)
					(thickness 0.1524)
				)
			)
		)
		(property "Device Type" "R402H16"
			(at 0.064008 -5.517896 180)
			(unlocked yes)
			(layer "F.Fab")
			(hide yes)
			(effects
				(font
					(size 1.016 1.016)
					(thickness 0.1524)
				)
			)
		)
		(duplicate_pad_numbers_are_jumpers no)
		(fp_line
			(start 0.508 -0.9398)
			(end -0.508 -0.9398)
			(stroke
				(width 0.1524)
				(type default)
			)
			(layer "F.SilkS")
		)
		(fp_line
			(start -0.508 -0.9398)
			(end -0.508 0.9398)
			(stroke
				(width 0.1524)
				(type default)
			)
			(layer "F.SilkS")
		)
		(fp_rect
			(start -0.508 0.9398)
			(end 0.508 -0.9398)
			(stroke
				(width 0)
				(type default)
			)
			(fill no)
			(layer "F.CrtYd")
		)
		(fp_rect
			(start -0.508 0.9398)
			(end 0.508 -0.9398)
			(stroke
				(width 0)
				(type default)
			)
			(fill no)
			(layer "F.Fab")
		)
		(pad "1" smd custom
			(at 0 -0.4445 180)
			(size 0.1397 0.1397)
			(layers "F.Cu" "F.Mask" "F.Paste")
			(net "SAS_FAULT_LED13")
			(options
				(clearance outline)
				(anchor circle)
			)
			(primitives
				(gr_poly
					(pts
						(arc
							(start -0.1778 -0.2794)
							(mid -0.249642 -0.249642)
							(end -0.2794 -0.1778)
						)
						(arc
							(start -0.2794 0.1778)
							(mid -0.249642 0.249642)
							(end -0.1778 0.2794)
						)
						(arc
							(start 0.1778 0.2794)
							(mid 0.249642 0.249642)
							(end 0.2794 0.1778)
						)
						(arc
							(start 0.2794 -0.1778)
							(mid 0.249642 -0.249642)
							(end 0.1778 -0.2794)
						)
					)
					(width 0)
					(fill yes)
				)
			)
		)
		(pad "2" smd custom
			(at 0 0.4445 180)
			(size 0.1397 0.1397)
			(layers "F.Cu" "F.Mask" "F.Paste")
			(net "SAS_HDD_LED_13")
			(options
				(clearance outline)
				(anchor circle)
			)
			(primitives
				(gr_poly
					(pts
						(arc
							(start -0.1778 -0.2794)
							(mid -0.249642 -0.249642)
							(end -0.2794 -0.1778)
						)
						(arc
							(start -0.2794 0.1778)
							(mid -0.249642 0.249642)
							(end -0.1778 0.2794)
						)
						(arc
							(start 0.1778 0.2794)
							(mid 0.249642 0.249642)
							(end 0.2794 0.1778)
						)
						(arc
							(start 0.2794 -0.1778)
							(mid 0.249642 -0.249642)
							(end 0.1778 -0.2794)
						)
					)
					(width 0)
					(fill yes)
				)
			)
		)
	)
)
